(kicad_pcb
	(version 20260206)
	(generator "pcbnew")
	(generator_version "10.0")
	(general
		(thickness 1.6)
		(legacy_teardrops no)
	)
	(paper "A4")
	(title_block
		(title "Bryce Canyon_IOM_IOC_16318-2_OCP.brd")
		(comment 1 "Bryce Canyon / footprints 44-51 of 1605")
	)
	(layers
		(0 "F.Cu" signal "TOP")
		(4 "In1.Cu" signal "L2GND")
		(6 "In2.Cu" signal "L3")
		(8 "In3.Cu" signal "L4VCC")
		(10 "In4.Cu" signal "L5VCC")
		(12 "In5.Cu" signal "L6")
		(14 "In6.Cu" signal "L7GND")
		(2 "B.Cu" signal "BOTTOM")
		(9 "F.Adhes" user "F.Adhesive")
		(11 "B.Adhes" user "B.Adhesive")
		(13 "F.Paste" user "Package Geometry/Pastemask Top")
		(15 "B.Paste" user "Package Geometry/Pastemask Bottom")
		(5 "F.SilkS" user "Ref Des/Silkscreen Top")
		(7 "B.SilkS" user "Ref Des/Silkscreen Bottom")
		(1 "F.Mask" user "Board Geometry/Soldermask Top")
		(3 "B.Mask" user "Board Geometry/Soldermask Bottom")
		(17 "Dwgs.User" user "User.Drawings")
		(19 "Cmts.User" user "User.Comments")
		(21 "Eco1.User" user "User.Eco1")
		(23 "Eco2.User" user "User.Eco2")
		(25 "Edge.Cuts" user "Board Geometry/Outline")
		(27 "Margin" user)
		(31 "F.CrtYd" user "Package Geometry/Place Bound Top")
		(29 "B.CrtYd" user "Package Geometry/Place Bound Bottom")
		(35 "F.Fab" user "Ref Des/Assembly Top")
		(33 "B.Fab" user "Ref Des/Assembly Bottom")
	)
	(footprint ""
		(layer "F.Cu")
		(at 174.4345 -120.239536 90)
		(property "Reference" "PQ4"
			(at 0 0 90)
			(layer "F.SilkS")
			(hide yes)
			(effects
				(font
					(size 1.27 1.27)
				)
			)
		)
		(property "Value" "2N7002K-1-GP"
			(at 0.127 -8.9662 90)
			(unlocked yes)
			(layer "F.Fab")
			(hide yes)
			(effects
				(font
					(size 1.016 1.016)
					(thickness 0.1524)
				)
			)
		)
		(property "Device Type" "SOT23DGS2D4H44"
			(at 0.127 -10.4902 90)
			(unlocked yes)
			(layer "F.Fab")
			(hide yes)
			(effects
				(font
					(size 1.016 1.016)
					(thickness 0.1524)
				)
			)
		)
		(duplicate_pad_numbers_are_jumpers no)
		(fp_line
			(start 1.651 -1.778)
			(end -1.651 -1.778)
			(stroke
				(width 0.1524)
				(type default)
			)
			(layer "F.SilkS")
		)
		(fp_line
			(start -1.651 -1.778)
			(end -1.651 1.778)
			(stroke
				(width 0.1524)
				(type default)
			)
			(layer "F.SilkS")
		)
		(fp_line
			(start 1.651 1.778)
			(end 1.651 -1.778)
			(stroke
				(width 0.1524)
				(type default)
			)
			(layer "F.SilkS")
		)
		(fp_line
			(start -1.651 1.778)
			(end 1.651 1.778)
			(stroke
				(width 0.1524)
				(type default)
			)
			(layer "F.SilkS")
		)
		(fp_poly
			(pts
				(xy -1.778 1.8796) (xy -1.778 -1.8796) (xy 1.778 -1.8796) (xy 1.778 1.8796)
			)
			(stroke
				(width 0)
				(type default)
			)
			(fill no)
			(layer "F.CrtYd")
		)
		(fp_poly
			(pts
				(xy -1.778 1.8796) (xy -1.778 -1.8796) (xy 1.778 -1.8796) (xy 1.778 1.8796)
			)
			(stroke
				(width 0)
				(type default)
			)
			(fill no)
			(layer "F.Fab")
		)
		(pad "D" smd custom
			(at 0 -0.9525 90)
			(size 0.1905 0.1905)
			(layers "F.Cu" "F.Mask" "F.Paste")
			(net "PQ4_D")
			(options
				(clearance outline)
				(anchor circle)
			)
			(primitives
				(gr_poly
					(pts
						(arc
							(start -0.1778 0.5715)
							(mid -0.321484 0.511984)
							(end -0.381 0.3683)
						)
						(arc
							(start -0.381 -0.3683)
							(mid -0.321484 -0.511984)
							(end -0.1778 -0.5715)
						)
						(arc
							(start 0.1778 -0.5715)
							(mid 0.321484 -0.511984)
							(end 0.381 -0.3683)
						)
						(arc
							(start 0.381 0.3683)
							(mid 0.321484 0.511984)
							(end 0.1778 0.5715)
						)
					)
					(width 0)
					(fill yes)
				)
			)
		)
		(pad "G" smd custom
			(at -0.98425 0.9525 90)
			(size 0.1905 0.1905)
			(layers "F.Cu" "F.Mask" "F.Paste")
			(net "PQ4_G")
			(options
				(clearance outline)
				(anchor circle)
			)
			(primitives
				(gr_poly
					(pts
						(arc
							(start -0.1778 0.5715)
							(mid -0.321484 0.511984)
							(end -0.381 0.3683)
						)
						(arc
							(start -0.381 -0.3683)
							(mid -0.321484 -0.511984)
							(end -0.1778 -0.5715)
						)
						(arc
							(start 0.1778 -0.5715)
							(mid 0.321484 -0.511984)
							(end 0.381 -0.3683)
						)
						(arc
							(start 0.381 0.3683)
							(mid 0.321484 0.511984)
							(end 0.1778 0.5715)
						)
					)
					(width 0)
					(fill yes)
				)
			)
		)
		(pad "S" smd custom
			(at 0.98425 0.9525 90)
			(size 0.1905 0.1905)
			(layers "F.Cu" "F.Mask" "F.Paste")
			(net "P1V8_EN")
			(options
				(clearance outline)
				(anchor circle)
			)
			(primitives
				(gr_poly
					(pts
						(arc
							(start -0.1778 0.5715)
							(mid -0.321484 0.511984)
							(end -0.381 0.3683)
						)
						(arc
							(start -0.381 -0.3683)
							(mid -0.321484 -0.511984)
							(end -0.1778 -0.5715)
						)
						(arc
							(start 0.1778 -0.5715)
							(mid 0.321484 -0.511984)
							(end 0.381 -0.3683)
						)
						(arc
							(start 0.381 0.3683)
							(mid 0.321484 0.511984)
							(end 0.1778 0.5715)
						)
					)
					(width 0)
					(fill yes)
				)
			)
		)
	)
	(footprint ""
		(layer "F.Cu")
		(at 176.784 -79.0194)
		(property "Reference" "TP90"
			(at 0 0 0)
			(layer "F.SilkS")
			(hide yes)
			(effects
				(font
					(size 1.27 1.27)
				)
			)
		)
		(property "Value" "TPAD28-2-GP"
			(at -0.0127 -1.6637 0)
			(unlocked yes)
			(layer "F.Fab")
			(hide yes)
			(effects
				(font
					(size 1.016 1.016)
					(thickness 0.1524)
				)
			)
		)
		(property "Device Type" "TPAD28"
			(at -0.0127 -3.1877 0)
			(unlocked yes)
			(layer "F.Fab")
			(hide yes)
			(effects
				(font
					(size 1.016 1.016)
					(thickness 0.1524)
				)
			)
		)
		(duplicate_pad_numbers_are_jumpers no)
		(fp_poly
			(pts
				(arc
					(start 0.3556 0)
					(mid -0.3556 0)
					(end 0.3556 0)
				)
			)
			(stroke
				(width 0)
				(type default)
			)
			(fill no)
			(layer "F.CrtYd")
		)
		(fp_poly
			(pts
				(arc
					(start 0.6096 0)
					(mid -0.6096 0)
					(end 0.6096 0)
				)
			)
			(stroke
				(width 0)
				(type default)
			)
			(fill no)
			(layer "F.Fab")
		)
		(pad "1" smd circle
			(at 0 0)
			(size 0.7112 0.7112)
			(layers "F.Cu" "F.Mask" "F.Paste")
			(net "IOC_GPIO_4")
		)
	)
	(footprint ""
		(layer "F.Cu")
		(at 168.6306 -106.0704 -90)
		(property "Reference" "C463"
			(at 0 0 270)
			(layer "F.SilkS")
			(hide yes)
			(effects
				(font
					(size 1.27 1.27)
				)
			)
		)
		(property "Value" "SC1U16V2KX-7-GP"
			(at 1.7526 -1.6002 270)
			(unlocked yes)
			(layer "F.Fab")
			(hide yes)
			(effects
				(font
					(size 1.016 1.016)
					(thickness 0.1524)
				)
			)
		)
		(property "Device Type" "C402-TO0D2H24"
			(at 1.7526 -3.1242 270)
			(unlocked yes)
			(layer "F.Fab")
			(hide yes)
			(effects
				(font
					(size 1.016 1.016)
					(thickness 0.1524)
				)
			)
		)
		(duplicate_pad_numbers_are_jumpers no)
		(fp_rect
			(start -0.4826 0.889)
			(end 0.4826 -0.889)
			(stroke
				(width 0)
				(type default)
			)
			(fill no)
			(layer "F.CrtYd")
		)
		(fp_rect
			(start -0.4826 0.889)
			(end 0.4826 -0.889)
			(stroke
				(width 0)
				(type default)
			)
			(fill no)
			(layer "F.Fab")
		)
		(pad "1" smd custom
			(at 0 -0.4572 270)
			(size 0.1524 0.1524)
			(layers "F.Cu" "F.Mask" "F.Paste")
			(net "P1V8")
			(options
				(clearance outline)
				(anchor circle)
			)
			(primitives
				(gr_poly
					(pts
						(arc
							(start -0.254 0.3048)
							(mid -0.325842 0.275042)
							(end -0.3556 0.2032)
						)
						(arc
							(start -0.3556 -0.2032)
							(mid -0.325842 -0.275042)
							(end -0.254 -0.3048)
						)
						(arc
							(start 0.254 -0.3048)
							(mid 0.325842 -0.275042)
							(end 0.3556 -0.2032)
						)
						(arc
							(start 0.3556 0.2032)
							(mid 0.325842 0.275042)
							(end 0.254 0.3048)
						)
					)
					(width 0)
					(fill yes)
				)
			)
		)
		(pad "2" smd custom
			(at 0 0.4572 270)
			(size 0.1524 0.1524)
			(layers "F.Cu" "F.Mask" "F.Paste")
			(net "GND")
			(options
				(clearance outline)
				(anchor circle)
			)
			(primitives
				(gr_poly
					(pts
						(arc
							(start -0.254 0.3048)
							(mid -0.325842 0.275042)
							(end -0.3556 0.2032)
						)
						(arc
							(start -0.3556 -0.2032)
							(mid -0.325842 -0.275042)
							(end -0.254 -0.3048)
						)
						(arc
							(start 0.254 -0.3048)
							(mid 0.325842 -0.275042)
							(end 0.3556 -0.2032)
						)
						(arc
							(start 0.3556 0.2032)
							(mid 0.325842 0.275042)
							(end 0.254 0.3048)
						)
					)
					(width 0)
					(fill yes)
				)
			)
		)
	)
	(footprint ""
		(layer "F.Cu")
		(at 209.876136 -127.9398)
		(property "Reference" "C254"
			(at 0 0 0)
			(layer "F.SilkS")
			(hide yes)
			(effects
				(font
					(size 1.27 1.27)
				)
			)
		)
		(property "Value" "SCD1U16V2KX-3GP"
			(at 1.1811 -2.7051 0)
			(unlocked yes)
			(layer "F.Fab")
			(hide yes)
			(effects
				(font
					(size 1.016 1.016)
					(thickness 0.1524)
				)
			)
		)
		(property "Device Type" "C402H22"
			(at 1.1811 -4.2291 0)
			(unlocked yes)
			(layer "F.Fab")
			(hide yes)
			(effects
				(font
					(size 1.016 1.016)
					(thickness 0.1524)
				)
			)
		)
		(duplicate_pad_numbers_are_jumpers no)
		(fp_rect
			(start -0.4318 0.9525)
			(end 0.4318 -0.9525)
			(stroke
				(width 0)
				(type default)
			)
			(fill no)
			(layer "F.CrtYd")
		)
		(fp_rect
			(start -0.4318 0.9525)
			(end 0.4318 -0.9525)
			(stroke
				(width 0)
				(type default)
			)
			(fill no)
			(layer "F.Fab")
		)
		(pad "1" smd custom
			(at 0 -0.4445)
			(size 0.1524 0.1524)
			(layers "F.Cu" "F.Mask" "F.Paste")
			(net "P1V8_STBY")
			(options
				(clearance outline)
				(anchor circle)
			)
			(primitives
				(gr_poly
					(pts
						(arc
							(start 0.3048 -0.2032)
							(mid 0.275042 -0.275042)
							(end 0.2032 -0.3048)
						)
						(arc
							(start -0.2032 -0.3048)
							(mid -0.275042 -0.275042)
							(end -0.3048 -0.2032)
						)
						(arc
							(start -0.3048 0.2032)
							(mid -0.275042 0.275042)
							(end -0.2032 0.3048)
						)
						(arc
							(start 0.2032 0.3048)
							(mid 0.275042 0.275042)
							(end 0.3048 0.2032)
						)
					)
					(width 0)
					(fill yes)
				)
			)
		)
		(pad "2" smd custom
			(at 0 0.4445)
			(size 0.1524 0.1524)
			(layers "F.Cu" "F.Mask" "F.Paste")
			(net "GND")
			(options
				(clearance outline)
				(anchor circle)
			)
			(primitives
				(gr_poly
					(pts
						(arc
							(start 0.3048 -0.2032)
							(mid 0.275042 -0.275042)
							(end 0.2032 -0.3048)
						)
						(arc
							(start -0.2032 -0.3048)
							(mid -0.275042 -0.275042)
							(end -0.3048 -0.2032)
						)
						(arc
							(start -0.3048 0.2032)
							(mid -0.275042 0.275042)
							(end -0.2032 0.3048)
						)
						(arc
							(start 0.2032 0.3048)
							(mid 0.275042 0.275042)
							(end 0.3048 0.2032)
						)
					)
					(width 0)
					(fill yes)
				)
			)
		)
	)
	(footprint ""
		(layer "F.Cu")
		(at 33.693354 -186.99861)
		(property "Reference" "R490"
			(at 0 0 0)
			(layer "F.SilkS")
			(hide yes)
			(effects
				(font
					(size 1.27 1.27)
				)
			)
		)
		(property "Value" "3D01R5F-GP"
			(at 0 -8.9535 0)
			(unlocked yes)
			(layer "F.Fab")
			(hide yes)
			(effects
				(font
					(size 1.27 1.016)
					(thickness 0.1524)
				)
			)
		)
		(property "Device Type" "R805H24"
			(at 0 -10.6299 0)
			(unlocked yes)
			(layer "F.Fab")
			(hide yes)
			(effects
				(font
					(size 1.27 1.016)
					(thickness 0.1524)
				)
			)
		)
		(duplicate_pad_numbers_are_jumpers no)
		(fp_line
			(start -0.889 -1.7018)
			(end -0.889 0.2794)
			(stroke
				(width 0.1524)
				(type default)
			)
			(layer "F.SilkS")
		)
		(fp_line
			(start -0.889 0.0762)
			(end -0.889 1.7018)
			(stroke
				(width 0.1524)
				(type default)
			)
			(layer "F.SilkS")
		)
		(fp_line
			(start -0.889 1.7018)
			(end 0.889 1.7018)
			(stroke
				(width 0.1524)
				(type default)
			)
			(layer "F.SilkS")
		)
		(fp_line
			(start 0.889 -1.7018)
			(end -0.889 -1.7018)
			(stroke
				(width 0.1524)
				(type default)
			)
			(layer "F.SilkS")
		)
		(fp_line
			(start 0.889 -1.7018)
			(end 0.889 -0.381)
			(stroke
				(width 0.1524)
				(type default)
			)
			(layer "F.SilkS")
		)
		(fp_line
			(start 0.889 1.7018)
			(end 0.889 -0.508)
			(stroke
				(width 0.1524)
				(type default)
			)
			(layer "F.SilkS")
		)
		(fp_poly
			(pts
				(xy 0.9652 -1.778) (xy 0.9652 1.778) (xy -0.9652 1.778) (xy -0.9652 -1.778)
			)
			(stroke
				(width 0)
				(type default)
			)
			(fill no)
			(layer "F.CrtYd")
		)
		(fp_rect
			(start -0.9652 1.778)
			(end 0.9652 -1.778)
			(stroke
				(width 0)
				(type default)
			)
			(fill no)
			(layer "F.Fab")
		)
		(pad "1" smd rect
			(at 0 -0.9652)
			(size 1.397 1.143)
			(layers "F.Cu" "F.Mask" "F.Paste")
			(net "P3V3_SNB")
		)
		(pad "2" smd rect
			(at 0 0.9652)
			(size 1.397 1.143)
			(layers "F.Cu" "F.Mask" "F.Paste")
			(net "GND")
		)
	)
	(footprint ""
		(layer "F.Cu")
		(at 94.488 -28.194 90)
		(property "Reference" "C2"
			(at 0 0 90)
			(layer "F.SilkS")
			(hide yes)
			(effects
				(font
					(size 1.27 1.27)
				)
			)
		)
		(property "Value" "SC1U16V3KX-5GP"
			(at 0 -2.8194 90)
			(unlocked yes)
			(layer "F.Fab")
			(hide yes)
			(effects
				(font
					(size 1.016 1.016)
					(thickness 0.1524)
				)
			)
		)
		(property "Device Type" "C603H36"
			(at 0 -4.3434 90)
			(unlocked yes)
			(layer "F.Fab")
			(hide yes)
			(effects
				(font
					(size 1.016 1.016)
					(thickness 0.1524)
				)
			)
		)
		(duplicate_pad_numbers_are_jumpers no)
		(fp_line
			(start 0.508 0)
			(end -0.508 0)
			(stroke
				(width 0.2032)
				(type default)
			)
			(layer "F.SilkS")
		)
		(fp_rect
			(start -0.5842 1.3335)
			(end 0.5842 -1.3335)
			(stroke
				(width 0)
				(type default)
			)
			(fill no)
			(layer "F.CrtYd")
		)
		(fp_rect
			(start -0.5842 1.3335)
			(end 0.5842 -1.3335)
			(stroke
				(width 0)
				(type default)
			)
			(fill no)
			(layer "F.Fab")
		)
		(pad "1" smd custom
			(at 0 -0.762 90)
			(size 0.2159 0.2159)
			(layers "F.Cu" "F.Mask" "F.Paste")
			(net "P5V_USB")
			(options
				(clearance outline)
				(anchor circle)
			)
			(primitives
				(gr_poly
					(pts
						(arc
							(start -0.3302 -0.4318)
							(mid -0.402042 -0.402042)
							(end -0.4318 -0.3302)
						)
						(arc
							(start -0.4318 0.3302)
							(mid -0.402042 0.402042)
							(end -0.3302 0.4318)
						)
						(arc
							(start 0.3302 0.4318)
							(mid 0.402042 0.402042)
							(end 0.4318 0.3302)
						)
						(arc
							(start 0.4318 -0.3302)
							(mid 0.402042 -0.402042)
							(end 0.3302 -0.4318)
						)
					)
					(width 0)
					(fill yes)
				)
			)
		)
		(pad "2" smd custom
			(at 0 0.762 90)
			(size 0.2159 0.2159)
			(layers "F.Cu" "F.Mask" "F.Paste")
			(net "GND")
			(options
				(clearance outline)
				(anchor circle)
			)
			(primitives
				(gr_poly
					(pts
						(arc
							(start -0.3302 -0.4318)
							(mid -0.402042 -0.402042)
							(end -0.4318 -0.3302)
						)
						(arc
							(start -0.4318 0.3302)
							(mid -0.402042 0.402042)
							(end -0.3302 0.4318)
						)
						(arc
							(start 0.3302 0.4318)
							(mid 0.402042 0.402042)
							(end 0.4318 0.3302)
						)
						(arc
							(start 0.4318 -0.3302)
							(mid 0.402042 -0.402042)
							(end 0.3302 -0.4318)
						)
					)
					(width 0)
					(fill yes)
				)
			)
		)
	)
	(footprint ""
		(layer "F.Cu")
		(at 74.0918 -185.9026)
		(property "Reference" "R507"
			(at 0 0 0)
			(layer "F.SilkS")
			(hide yes)
			(effects
				(font
					(size 1.27 1.27)
				)
			)
		)
		(property "Value" "10KR2F-2-GP"
			(at 0.064008 -3.993896 0)
			(unlocked yes)
			(layer "F.Fab")
			(hide yes)
			(effects
				(font
					(size 1.016 1.016)
					(thickness 0.1524)
				)
			)
		)
		(property "Device Type" "R402H16"
			(at 0.064008 -5.517896 0)
			(unlocked yes)
			(layer "F.Fab")
			(hide yes)
			(effects
				(font
					(size 1.016 1.016)
					(thickness 0.1524)
				)
			)
		)
		(duplicate_pad_numbers_are_jumpers no)
		(fp_line
			(start -0.508 -0.9398)
			(end -0.508 0.9398)
			(stroke
				(width 0.1524)
				(type default)
			)
			(layer "F.SilkS")
		)
		(fp_line
			(start 0.508 -0.9398)
			(end -0.508 -0.9398)
			(stroke
				(width 0.1524)
				(type default)
			)
			(layer "F.SilkS")
		)
		(fp_rect
			(start -0.508 0.9398)
			(end 0.508 -0.9398)
			(stroke
				(width 0)
				(type default)
			)
			(fill no)
			(layer "F.CrtYd")
		)
		(fp_rect
			(start -0.508 0.9398)
			(end 0.508 -0.9398)
			(stroke
				(width 0)
				(type default)
			)
			(fill no)
			(layer "F.Fab")
		)
		(pad "1" smd custom
			(at 0 -0.4445)
			(size 0.1397 0.1397)
			(layers "F.Cu" "F.Mask" "F.Paste")
			(net "P3V3_STBY")
			(options
				(clearance outline)
				(anchor circle)
			)
			(primitives
				(gr_poly
					(pts
						(arc
							(start -0.1778 -0.2794)
							(mid -0.249642 -0.249642)
							(end -0.2794 -0.1778)
						)
						(arc
							(start -0.2794 0.1778)
							(mid -0.249642 0.249642)
							(end -0.1778 0.2794)
						)
						(arc
							(start 0.1778 0.2794)
							(mid 0.249642 0.249642)
							(end 0.2794 0.1778)
						)
						(arc
							(start 0.2794 -0.1778)
							(mid 0.249642 -0.249642)
							(end 0.1778 -0.2794)
						)
					)
					(width 0)
					(fill yes)
				)
			)
		)
		(pad "2" smd custom
			(at 0 0.4445)
			(size 0.1397 0.1397)
			(layers "F.Cu" "F.Mask" "F.Paste")
			(net "PWRGD_P2V5_STBY")
			(options
				(clearance outline)
				(anchor circle)
			)
			(primitives
				(gr_poly
					(pts
						(arc
							(start -0.1778 -0.2794)
							(mid -0.249642 -0.249642)
							(end -0.2794 -0.1778)
						)
						(arc
							(start -0.2794 0.1778)
							(mid -0.249642 0.249642)
							(end -0.1778 0.2794)
						)
						(arc
							(start 0.1778 0.2794)
							(mid 0.249642 0.249642)
							(end 0.2794 0.1778)
						)
						(arc
							(start 0.2794 -0.1778)
							(mid 0.249642 -0.249642)
							(end 0.1778 -0.2794)
						)
					)
					(width 0)
					(fill yes)
				)
			)
		)
	)
	(footprint ""
		(layer "F.Cu")
		(at 132.5372 -13.1064)
		(property "Reference" "C134"
			(at 0 0 0)
			(layer "F.SilkS")
			(hide yes)
			(effects
				(font
					(size 1.27 1.27)
				)
			)
		)
		(property "Value" "SCD015U25V2KX-GP"
			(at 1.1811 -2.7051 0)
			(unlocked yes)
			(layer "F.Fab")
			(hide yes)
			(effects
				(font
					(size 1.016 1.016)
					(thickness 0.1524)
				)
			)
		)
		(property "Device Type" "C402H22"
			(at 1.1811 -4.2291 0)
			(unlocked yes)
			(layer "F.Fab")
			(hide yes)
			(effects
				(font
					(size 1.016 1.016)
					(thickness 0.1524)
				)
			)
		)
		(duplicate_pad_numbers_are_jumpers no)
		(fp_rect
			(start -0.4318 0.9525)
			(end 0.4318 -0.9525)
			(stroke
				(width 0)
				(type default)
			)
			(fill no)
			(layer "F.CrtYd")
		)
		(fp_rect
			(start -0.4318 0.9525)
			(end 0.4318 -0.9525)
			(stroke
				(width 0)
				(type default)
			)
			(fill no)
			(layer "F.Fab")
		)
		(pad "1" smd custom
			(at 0 -0.4445)
			(size 0.1524 0.1524)
			(layers "F.Cu" "F.Mask" "F.Paste")
			(net "ADM1278_HS_P")
			(options
				(clearance outline)
				(anchor circle)
			)
			(primitives
				(gr_poly
					(pts
						(arc
							(start 0.3048 -0.2032)
							(mid 0.275042 -0.275042)
							(end 0.2032 -0.3048)
						)
						(arc
							(start -0.2032 -0.3048)
							(mid -0.275042 -0.275042)
							(end -0.3048 -0.2032)
						)
						(arc
							(start -0.3048 0.2032)
							(mid -0.275042 0.275042)
							(end -0.2032 0.3048)
						)
						(arc
							(start 0.2032 0.3048)
							(mid 0.275042 0.275042)
							(end 0.3048 0.2032)
						)
					)
					(width 0)
					(fill yes)
				)
			)
		)
		(pad "2" smd custom
			(at 0 0.4445)
			(size 0.1524 0.1524)
			(layers "F.Cu" "F.Mask" "F.Paste")
			(net "ADM1278_HS_N")
			(options
				(clearance outline)
				(anchor circle)
			)
			(primitives
				(gr_poly
					(pts
						(arc
							(start 0.3048 -0.2032)
							(mid 0.275042 -0.275042)
							(end 0.2032 -0.3048)
						)
						(arc
							(start -0.2032 -0.3048)
							(mid -0.275042 -0.275042)
							(end -0.3048 -0.2032)
						)
						(arc
							(start -0.3048 0.2032)
							(mid -0.275042 0.275042)
							(end -0.2032 0.3048)
						)
						(arc
							(start 0.2032 0.3048)
							(mid 0.275042 0.275042)
							(end 0.3048 0.2032)
						)
					)
					(width 0)
					(fill yes)
				)
			)
		)
	)
)
